FILE_TYPE = CONNECTIVITY;
{Allegro Design Entry HDL 16.6-p007 (v16-6-112F) 10/10/2012}
"PAGE_NUMBER" = 177;
0"NC";
1"P3V3\g";
2"GND\g";
3"P5V_STBY\g";
4"P3V3\g";
5"GND\g";
6"GND\g";
7"P3V3_STBY\g";
8"P3V3_STBY\g";
9"P3V3_STBY\g";
10"GND\g";
11"P3V3\g";
12"LED_SATA_ACT_R_N";
13"LED_PCH_SSATA_HDD_N";
14"LED_SAS_ACT_R_N";
15"FM_BMC_FAULT_LED_N";
16"LED_PCH_SATA_HDD_N";
17"FM_BMC_FAULT_LED";
18"FP_LED_HDD_ACTIVITY_AND_N";
19"FP_LED_HDD_ACTIVITY_AND_R_N";
20"FM_RED_LED_CATHODE";
21"FM_RED_LED_ANODE";
22"LED_P5V_STBY";
%"P3V3"
"1","(-6975,6775)","0","mstr_symbols","I10";
;
HDL_POWER"P3V3"
BODY_TYPE"PLUMBING"
ROOM"SB"
CDS_LIB"mstr_symbols"
SIZE"1B"
VOLTAGE"+3.3";
"G\NAC"1;
%"CAP_A"
"1","(-5625,5425)","0","dev_discrete","I20";
;
ROOM"MIO_CHASSIS"
$SEC"1"
CDS_SEC"1"
CDS_LIB"dev_discrete"
CDS_LOCATION"C1M3"
MATERIAL"X6S"
VOLTAGE"6.3V"
PACK_TYPE"0402V"
TOLERANCE"10%"
VALUE"1.0UF"
PART_NUMBER"D97712-004"
LOCATION"C1M3";
"B"
$PN"2"5;
"A"
$PN"1"4;
%"RES"
"1","(-7550,6225)","0","mstr_discrete","I3";
;
ROOM"MIO_CHASSIS"
CDS_LOCATION"R1M13"
$SEC"1"
CDS_SEC"1"
CDS_LIB"mstr_discrete"
TOLERANCE"5%"
PART_NUMBER"G21497-005"
LOCATION"R1M13"
WATTAGE"1/16W"
PACK_TYPE"0402"
MATERIAL"CHIP"
VALUE"0.0";
"B"
$PN"2"14;
"A"
$PN"1"13;
%"GND"
"1","(-3825,8250)","0","mstr_symbols","I30";
;
HDL_POWER"GND"
BODY_TYPE"PLUMBING"
ROOM"DEBUG"
SIZE"1B"
CDS_LIB"mstr_symbols"
VOLTAGE"0";
"A\NAC"2;
%"LED"
"2","(-3825,8475)","0","mstr_discrete","I31";
;
CDS_SEC"1"
ROOM"MIO_CHASSIS"
CDS_LOCATION"DS9A6"
SEC"1"
CDS_LIB"mstr_discrete"
SEC_TYPE"A1LF"
PACK_TYPE"A1LF"
COLOR"GREEN"
MATERIAL"IC"
PART_NUMBER"C97278-010"
LOCATION"DS9A6";
"C"
$PN"2"2;
"A"
$PN"1"22;
%"RES"
"2","(-3825,8850)","0","mstr_discrete","I33";
;
ROOM"MIO_CHASSIS"
CDS_LOCATION"R1L37"
$SEC"1"
CDS_SEC"1"
SIGNAL_MODEL"DEFAULT_RESISTOR_332OHM_2_1"
CDS_LIB"mstr_discrete"
WATTAGE"1/16W"
MATERIAL"CHIP"
PACK_TYPE"0402"
TOLERANCE"1%"
VALUE"301.0"
PART_NUMBER"G21796-076"
LOCATION"R1L37";
"A"
$PN"1"3;
"B"
$PN"2"22;
%"P5V_STBY"
"1","(-3825,9050)","0","mstr_symbols","I36";
;
HDL_POWER"P5V_STBY"
BODY_TYPE"PLUMBING"
SIZE"1B"
CDS_LIB"mstr_symbols"
VOLTAGE"5.0V";
"G\NAC"3;
%"LED"
"3","(-5550,6275)","0","mstr_discrete","I42";
;
CDS_SEC"1"
ROOM"MIO_CHASSIS"
CDS_LOCATION"DS9A2"
SEC"1"
CDS_LIB"mstr_discrete"
SEC_TYPE"1NCLF"
PACK_TYPE"1NCLF"
COLOR"GREEN"
MATERIAL"IC"
PART_NUMBER"C96565-011"
LOCATION"DS9A2";
"A"
$PN"2"19;
"C"
$PN"1"18;
%"RES"
"2","(-4675,6600)","0","mstr_discrete","I43";
;
CDS_SEC"1"
ROOM"MIO_CHASSIS"
CDS_LOCATION"R1L21"
SEC"1"
SEC_TYPE"0402"
CDS_LIB"mstr_discrete"
WATTAGE"1/16W"
MATERIAL"CHIP"
PACK_TYPE"0402"
TOLERANCE"1.0%"
VALUE"64.9"
PART_NUMBER"G21796-298"
LOCATION"R1L21";
"A"
$PN"1"11;
"B"
$PN"2"19;
%"P3V3"
"1","(-5625,5725)","0","mstr_symbols","I45";
;
HDL_POWER"P3V3"
BODY_TYPE"PLUMBING"
ROOM"SM_CONTROLLER"
SIZE"1B"
CDS_LIB"mstr_symbols"
VOLTAGE"+3.3";
"G\NAC"4;
%"GND"
"1","(-5625,5075)","0","mstr_symbols","I46";
;
HDL_POWER"GND"
BODY_TYPE"PLUMBING"
ROOM"MIO_CHASSIS"
SIZE"1B"
CDS_LIB"mstr_symbols"
VOLTAGE"0";
"A\NAC"5;
%"RES"
"1","(-7750,6325)","0","mstr_discrete","I6";
;
ROOM"MIO_CHASSIS"
CDS_LOCATION"R1M10"
$SEC"1"
CDS_SEC"1"
CDS_LIB"mstr_discrete"
WATTAGE"1/16W"
PACK_TYPE"0402"
LOCATION"R1M10"
MATERIAL"CHIP"
TOLERANCE"5%"
VALUE"0.0"
PART_NUMBER"G21497-005";
"B"
$PN"2"12;
"A"
$PN"1"16;
%"TTL1G08"
"1","(-6550,6275)","0","mstr_ttl","I70";
;
CDS_SEC"1"
ROOM"MIO_CHASSIS"
CDS_LOCATION"U1M1"
SEC"1"
BOM_COST"MIO_CHASSIS"
SEC_TYPE"SOTLF"
CDS_LIB"mstr_ttl"
PART_NUMBER"D10321-001"
PACK_TYPE"SOTLF"
MATERIAL"IC"
VALUE"NC7SZ08"
LOCATION"U1M1"
POWER_GROUP"VCC=P3V3;GND=GND;";
"Y <SIZE-1..0>"
$PN"4"18;
"B <SIZE-1..0>"
$PN"2"14;
"A <SIZE-1..0>"
$PN"1"12;
%"LED"
"2","(-7200,8475)","0","mstr_discrete","I71";
;
CDS_SEC"1"
ROOM"BMC"
CDS_LOCATION"DS9F1"
SEC"1"
BOM_COST"SM_CONTROLLER"
CDS_LIB"mstr_discrete"
SEC_TYPE"A1"
PACK_TYPE"A1"
COLOR"RED"
MATERIAL"IC"
PART_NUMBER"D14725-005"
LOCATION"DS9F1";
"C"
$PN"2"20;
"A"
$PN"1"21;
%"RES"
"2","(-7200,8825)","0","mstr_discrete","I72";
;
CDS_SEC"1"
ROOM"BMC"
CDS_LOCATION"R9F28"
SEC"1"
BOM_COST"SM_CONTROLLER"
CDS_LIB"mstr_discrete"
SEC_TYPE"0402"
WATTAGE"1/16W"
MATERIAL"CHIP"
PACK_TYPE"0402"
TOLERANCE"1.0%"
VALUE"221"
PART_NUMBER"G21796-271"
LOCATION"R9F28";
"A"
$PN"1"8;
"B"
$PN"2"21;
%"GND"
"1","(-7200,7650)","0","mstr_symbols","I74";
;
HDL_POWER"GND"
BODY_TYPE"PLUMBING"
CDS_LIB"mstr_symbols"
SIZE"1B"
VOLTAGE"0.0V";
"A\NAC"6;
%"RES"
"2","(-8475,7850)","0","mstr_discrete","I76";
;
CDS_SEC"1"
ROOM"BMC"
CDS_LOCATION"R9F30"
SEC"1"
SEC_TYPE"0402"
CDS_LIB"mstr_discrete"
BOM_COST"SM_CONTROLLER"
WATTAGE"1/16W"
MATERIAL"CHIP"
PACK_TYPE"0402"
TOLERANCE"1%"
VALUE"4.75K"
PART_NUMBER"G21796-072"
LOCATION"R9F30";
"A"
$PN"1"7;
"B"
$PN"2"15;
%"P3V3_STBY"
"1","(-8475,8125)","0","mstr_symbols","I77";
;
HDL_POWER"P3V3_STBY"
BODY_TYPE"PLUMBING"
SIZE"1B"
CDS_LIB"mstr_symbols"
VOLTAGE"3.3V";
"G\NAC"7;
%"P3V3_STBY"
"1","(-7200,9125)","0","mstr_symbols","I78";
;
HDL_POWER"P3V3_STBY"
BODY_TYPE"PLUMBING"
CDS_LIB"mstr_symbols"
SIZE"1B"
VOLTAGE"3.3V";
"G\NAC"8;
%"FET_N_DUAL"
"5","(-7200,8050)","0","mstr_discrete","I79";
;
CDS_SEC"2"
ROOM"BMC"
CDS_LOCATION"Q9F1"
SEC"2"
SEC_TYPE"SMLF"
BOM_COST"SM_CONTROLLER"
CDS_LIB"mstr_discrete"
PACK_TYPE"SMLF"
MATERIAL"FET"
VALUE"NTJD4001N"
PART_NUMBER"E40049-001"
LOCATION"Q9F1";
"GATE <SIZE -1..0>"
$PN"5"17;
"SOURCE <SIZE-1..0>"
$PN"4"6;
"DRAIN <SIZE -1..0>"
$PN"3"20;
%"RES"
"2","(-6975,6550)","0","mstr_discrete","I8";
;
CDS_SEC"1"
ROOM"MIO_CHASSIS"
CDS_LOCATION"R1M12"
SEC"1"
CDS_LIB"mstr_discrete"
SEC_TYPE"0402"
MATERIAL"CHIP"
PART_NUMBER"G21796-016"
WATTAGE"1/16W"
PACK_TYPE"0402"
TOLERANCE"1%"
VALUE"10.0K"
LOCATION"R1M12";
"A"
$PN"1"1;
"B"
$PN"2"14;
%"FET_N_DUAL"
"5","(-7800,7675)","0","mstr_discrete","I80";
;
CDS_SEC"1"
ROOM"BMC"
CDS_LOCATION"Q9F1"
SEC"1"
BOM_COST"SM_CONTROLLER"
SEC_TYPE"SMLF"
CDS_LIB"mstr_discrete"
PACK_TYPE"SMLF"
MATERIAL"FET"
VALUE"NTJD4001N"
PART_NUMBER"E40049-001"
LOCATION"Q9F1";
"GATE <SIZE -1..0>"
$PN"2"15;
"SOURCE <SIZE-1..0>"
$PN"1"10;
"DRAIN <SIZE -1..0>"
$PN"6"17;
%"P3V3_STBY"
"1","(-7800,8500)","0","mstr_symbols","I81";
;
HDL_POWER"P3V3_STBY"
BODY_TYPE"PLUMBING"
CDS_LIB"mstr_symbols"
SIZE"1B"
VOLTAGE"3.3V";
"G\NAC"9;
%"RES"
"2","(-7800,8225)","0","mstr_discrete","I82";
;
CDS_SEC"1"
ROOM"BMC"
CDS_LOCATION"R9F52"
SEC"1"
BOM_COST"SM_CONTROLLER"
CDS_LIB"mstr_discrete"
SEC_TYPE"0402"
WATTAGE"1/16W"
MATERIAL"CHIP"
PACK_TYPE"0402"
TOLERANCE"1%"
VALUE"4.75K"
PART_NUMBER"G21796-072"
LOCATION"R9F52";
"A"
$PN"1"9;
"B"
$PN"2"17;
%"GND"
"1","(-7800,7325)","0","mstr_symbols","I83";
;
HDL_POWER"GND"
BODY_TYPE"PLUMBING"
SIZE"1B"
CDS_LIB"mstr_symbols"
VOLTAGE"0.0V";
"A\NAC"10;
%"P3V3"
"1","(-4675,6925)","0","mstr_symbols","I85";
;
HDL_POWER"P3V3"
BODY_TYPE"PLUMBING"
SIZE"1B"
CDS_LIB"mstr_symbols"
VOLTAGE"3.3V";
"G\NAC"11;
%"RES"
"2","(-7025,6550)","2","mstr_discrete","I9";
;
CDS_SEC"1"
ROOM"MIO_CHASSIS"
CDS_LOCATION"R1M11"
SEC"1"
CDS_LIB"mstr_discrete"
SEC_TYPE"0402"
PART_NUMBER"G21796-016"
WATTAGE"1/16W"
VALUE"10.0K"
LOCATION"R1M11"
PACK_TYPE"0402"
MATERIAL"CHIP"
TOLERANCE"1%";
"A"
$PN"1"1;
"B"
$PN"2"12;
END.
